FILE_TYPE = CONNECTIVITY;
{Allegro Design Entry HDL 17.2-2016 S081 (4005846) 1/11/2022}
"PAGE_NUMBER" = 207;
0"NC";
1"P3V3_AUX\g";
2"P3V3_AUX\g";
3"P3V3_AUX\g";
4"GND\g";
5"GND\g";
6"GND\g";
7"LED_CPU_RMCA_CATERR";
8"FM_PLD_HEARTBEAT_LVC3_D"CDS_PHYS_NET_NAME"FM_PLD_HEARTBEAT_LVC3_D";
9"FM_PLD_HEARTBEAT_LVC3"CDS_PHYS_NET_NAME"FM_PLD_HEARTBEAT_LVC3";
10"LED_CPU_RMCA_CATERR_R";
11"PU_PLD_HEARTBEAT_LVC3";
12"CPU_RMCA_CATERR_LVT3_N"CDS_PHYS_NET_NAME"CPU_RMCA_CATERR_LVT3_N";
13"FM_CPU_RMCA_CATERR_LVT3_R_N"CDS_PHYS_NET_NAME"FM_CPU_RMCA_CATERR_LVT3_R_N";
%"MOSFET_N"
"1","(-1525,4525)","0","pure_quanta","I236";
;
PART_NUMBER"BAM138K0000"
MATERIAL"IC"
VALUE"BSS138K"
$LOCATION"U89"
MANUF_PN"BSS138K"
PACK_TYPE"SMLF"
CDS_LIB"pure_quanta"
CDS_LMAN_SYM_OUTLINE"-50,50,100,-150"
CDS_LOCATION"U89"
$SEC"1"
CDS_SEC"1";
"GATE"
$PN"G"9;
"SOURCE"
$PN"S"5;
"DRAIN"
$PN"D"8;
%"UNIVERSAL_GND"
"1","(-1475,4125)","0","logical_power","I237";
;
CDS_LIB"logical_power"
HDL_POWER"GND"
ROOM"IO_SLOT";
"A"5;
%"UNIVERSAL_POWER"
"1","(-4675,5050)","0","logical_power","I240";
;
HDL_POWER"P3V3_AUX"
CDS_LIB"logical_power";
"A"2;
%"UNIVERSAL_GND"
"1","(1300,1625)","0","logical_power","I267";
;
CDS_LIB"logical_power"
HDL_POWER"GND"
ROOM"IO_SLOT";
"A"4;
%"Q_RES"
"1","(-50,950)","0","pure_quanta","I268";
;
PART_NUMBER"CS02202JB09"
PACK_TYPE"0402LF"
WATTAGE"1/16W"
VALUE"22"
MATERIAL"CHIP"
TOLERANCE"5%"
$LOCATION"R2339"
CDS_LIB"pure_quanta"
CDS_LOCATION"R2339"
$SEC"1"
CDS_SEC"1";
"B"
$PN"2"6;
"A"
$PN"1"10;
%"UNIVERSAL_GND"
"1","(450,825)","0","logical_power","I269";
;
CDS_LIB"logical_power"
HDL_POWER"GND"
ROOM"IO_SLOT";
"A"6;
%"UNIVERSAL_POWER"
"1","(-1425,2300)","0","logical_power","I270";
;
HDL_POWER"P3V3_AUX"
CDS_LIB"logical_power";
"A"1;
%"MOSFET_NCH_GDS_ESD_PROTECTED"
"1","(-1450,1325)","0","pure_quanta","I272";
;
PART_NUMBER"BAM70020002"
VALUE"2N7002K"
MATERIAL"IC"
PART_TYPE"SMLF"
LOCATION"Q33"
CDS_LIB"pure_quanta"
CDS_LMAN_SYM_OUTLINE"-125,150,125,-150"
NEEDS_NO_SIZE"TRUE"
$SEC"1"
CDS_SEC"1";
"S"
$PN"S"10;
"G"
$PN"G"12;
"D"
$PN"D"7;
%"Q_RES"
"1","(-3150,1325)","0","pure_quanta","I273";
;
PART_NUMBER"CS00002JB13"
TOLERANCE"5%"
MATERIAL"CHIP"
WATTAGE"1/16W"
PACK_TYPE"0402LF"
VALUE"0"
$LOCATION"R365"
CDS_LIB"pure_quanta"
CDS_LOCATION"R365"
$SEC"1"
CDS_SEC"1";
"B"
$PN"2"12;
"A"
$PN"1"13;
%"UNIVERSAL_POWER"
"1","(-4625,1875)","0","logical_power","I274";
;
HDL_POWER"P3V3_AUX"
CDS_LIB"logical_power";
"A"3;
%"Q_RES"
"2","(-4625,1625)","0","pure_quanta","I275";
;
PART_NUMBER"CS31002FB08"
WATTAGE"1/16W"
TOLERANCE"1%"
VALUE"10K"
MATERIAL"CHIP"
PACK_TYPE"0402LF"
$LOCATION"R1841"
CDS_LIB"pure_quanta"
CDS_LOCATION"R1841"
$SEC"1"
CDS_SEC"1";
"A"
$PN"1"3;
"B"
$PN"2"13;
%"Q_LED"
"1","(-3050,4700)","0","pure_quanta","I277";
;
PART_NUMBER"BEBL0172Z00"
MATERIAL"IC"
MANUF_PN"LTST-C281TBKT-5A"
PACK_TYPE"SMLF"
COLOR"LED_BLUE"
LOCATION"D0"
CDS_LIB"pure_quanta"
NEEDS_NO_SIZE"TRUE"
$SEC"1"
CDS_SEC"1";
"A"
$PN"A"11;
"C"
$PN"C"8;
%"Q_RES"
"1","(-4250,4700)","0","pure_quanta","I278";
;
PART_NUMBER"CS11302FB03"
VALUE"130"
TOLERANCE"1%"
PACK_TYPE"0402LF"
WATTAGE"1/16W"
MATERIAL"CHIP"
LOCATION"R1195"
CDS_LIB"pure_quanta"
$SEC"1"
CDS_SEC"1";
"B"
$PN"2"11;
"A"
$PN"1"2;
%"Q_LED"
"1","(650,1775)","0","pure_quanta","I279";
;
PART_NUMBER"BEYL0159Z00"
PACK_TYPE"SMLF"
MATERIAL"IC"
MANUF_PN"LTST-C190KSKT-P"
COLOR"LED_YELLOW"
LOCATION"D6"
NEEDS_NO_SIZE"TRUE"
CDS_LIB"pure_quanta"
$SEC"1"
CDS_SEC"1";
"A"
$PN"A"7;
"C"
$PN"C"4;
%"Q_RES"
"2","(-1425,2000)","0","pure_quanta","I280";
;
PART_NUMBER"CS12492FB02"
VALUE"249"
PACK_TYPE"0402LF"
MATERIAL"CHIP"
WATTAGE"1/16W"
TOLERANCE"1%"
LOCATION"R366"
CDS_LIB"pure_quanta"
$SEC"1"
CDS_SEC"1";
"A"
$PN"1"1;
"B"
$PN"2"7;
END.
